(kicad_pcb
	(version 20260206)
	(generator "pcbnew")
	(generator_version "10.0")
	(general
		(thickness 1.6)
		(legacy_teardrops no)
	)
	(paper "A4")
	(title_block
		(title "peb — Lightning_PEB_BRD.brd")
		(comment 1 "Lightning (Wiwynn / Facebook NVMe JBOF) / footprints 503-509 of 2563")
	)
	(layers
		(0 "F.Cu" signal "TOP")
		(4 "In1.Cu" signal "L2GND")
		(6 "In2.Cu" signal "L3")
		(8 "In3.Cu" signal "L4VCC")
		(10 "In4.Cu" signal "L5VCC")
		(12 "In5.Cu" signal "L6")
		(14 "In6.Cu" signal "L7GND")
		(2 "B.Cu" signal "BOTTOM")
		(9 "F.Adhes" user "F.Adhesive")
		(11 "B.Adhes" user "B.Adhesive")
		(13 "F.Paste" user "Package Geometry/Pastemask Top")
		(15 "B.Paste" user "Package Geometry/Pastemask Bottom")
		(5 "F.SilkS" user "Ref Des/Silkscreen Top")
		(7 "B.SilkS" user "Ref Des/Silkscreen Bottom")
		(1 "F.Mask" user "Board Geometry/Soldermask Top")
		(3 "B.Mask" user "Board Geometry/Soldermask Bottom")
		(17 "Dwgs.User" user "User.Drawings")
		(19 "Cmts.User" user "User.Comments")
		(21 "Eco1.User" user "User.Eco1")
		(23 "Eco2.User" user "User.Eco2")
		(25 "Edge.Cuts" user "Board Geometry/Outline")
		(27 "Margin" user)
		(31 "F.CrtYd" user "Package Geometry/Place Bound Top")
		(29 "B.CrtYd" user "Package Geometry/Place Bound Bottom")
		(35 "F.Fab" user "Ref Des/Assembly Top")
		(33 "B.Fab" user "Ref Des/Assembly Bottom")
	)
	(footprint ""
		(layer "F.Cu")
		(at 16.256 -125.095 180)
		(property "Reference" "R17"
			(at 0 0 180)
			(layer "F.SilkS")
			(hide yes)
			(effects
				(font
					(size 1.27 1.27)
				)
			)
		)
		(property "Value" "0R2J-2-GP"
			(at 0.064008 -3.993896 180)
			(unlocked yes)
			(layer "F.Fab")
			(hide yes)
			(effects
				(font
					(size 1.016 1.016)
					(thickness 0.1524)
				)
			)
		)
		(property "Device Type" "R402H16"
			(at 0.064008 -5.517896 180)
			(unlocked yes)
			(layer "F.Fab")
			(hide yes)
			(effects
				(font
					(size 1.016 1.016)
					(thickness 0.1524)
				)
			)
		)
		(duplicate_pad_numbers_are_jumpers no)
		(fp_line
			(start 0.508 -0.9398)
			(end -0.508 -0.9398)
			(stroke
				(width 0.1524)
				(type default)
			)
			(layer "F.SilkS")
		)
		(fp_line
			(start -0.508 -0.9398)
			(end -0.508 0.9398)
			(stroke
				(width 0.1524)
				(type default)
			)
			(layer "F.SilkS")
		)
		(fp_rect
			(start -0.508 0.9398)
			(end 0.508 -0.9398)
			(stroke
				(width 0)
				(type default)
			)
			(fill no)
			(layer "F.CrtYd")
		)
		(fp_rect
			(start -0.508 0.9398)
			(end 0.508 -0.9398)
			(stroke
				(width 0)
				(type default)
			)
			(fill no)
			(layer "F.Fab")
		)
		(pad "1" smd custom
			(at 0 -0.4445 180)
			(size 0.1397 0.1397)
			(layers "F.Cu" "F.Mask" "F.Paste")
			(net "BMC_I2C2_MINI2_SDA")
			(options
				(clearance outline)
				(anchor circle)
			)
			(primitives
				(gr_poly
					(pts
						(arc
							(start -0.1778 -0.2794)
							(mid -0.249642 -0.249642)
							(end -0.2794 -0.1778)
						)
						(arc
							(start -0.2794 0.1778)
							(mid -0.249642 0.249642)
							(end -0.1778 0.2794)
						)
						(arc
							(start 0.1778 0.2794)
							(mid 0.249642 0.249642)
							(end 0.2794 0.1778)
						)
						(arc
							(start 0.2794 -0.1778)
							(mid 0.249642 -0.249642)
							(end 0.1778 -0.2794)
						)
					)
					(width 0)
					(fill yes)
				)
			)
		)
		(pad "2" smd custom
			(at 0 0.4445 180)
			(size 0.1397 0.1397)
			(layers "F.Cu" "F.Mask" "F.Paste")
			(net "BMC_I2C2_MINI2_SDA_S")
			(options
				(clearance outline)
				(anchor circle)
			)
			(primitives
				(gr_poly
					(pts
						(arc
							(start -0.1778 -0.2794)
							(mid -0.249642 -0.249642)
							(end -0.2794 -0.1778)
						)
						(arc
							(start -0.2794 0.1778)
							(mid -0.249642 0.249642)
							(end -0.1778 0.2794)
						)
						(arc
							(start 0.1778 0.2794)
							(mid 0.249642 0.249642)
							(end 0.2794 0.1778)
						)
						(arc
							(start 0.2794 -0.1778)
							(mid 0.249642 -0.249642)
							(end 0.1778 -0.2794)
						)
					)
					(width 0)
					(fill yes)
				)
			)
		)
	)
	(footprint ""
		(layer "F.Cu")
		(at 225.59518 -205.29042 -90)
		(property "Reference" "R9041"
			(at 0 0 270)
			(layer "F.SilkS")
			(hide yes)
			(effects
				(font
					(size 1.27 1.27)
				)
			)
		)
		(property "Value" "4K7R2F-GP"
			(at 0.064008 -3.993896 270)
			(unlocked yes)
			(layer "F.Fab")
			(hide yes)
			(effects
				(font
					(size 1.016 1.016)
					(thickness 0.1524)
				)
			)
		)
		(property "Device Type" "R402H16"
			(at 0.064008 -5.517896 270)
			(unlocked yes)
			(layer "F.Fab")
			(hide yes)
			(effects
				(font
					(size 1.016 1.016)
					(thickness 0.1524)
				)
			)
		)
		(duplicate_pad_numbers_are_jumpers no)
		(fp_line
			(start -0.508 -0.9398)
			(end -0.508 0.9398)
			(stroke
				(width 0.1524)
				(type default)
			)
			(layer "F.SilkS")
		)
		(fp_line
			(start 0.508 -0.9398)
			(end -0.508 -0.9398)
			(stroke
				(width 0.1524)
				(type default)
			)
			(layer "F.SilkS")
		)
		(fp_rect
			(start -0.508 0.9398)
			(end 0.508 -0.9398)
			(stroke
				(width 0)
				(type default)
			)
			(fill no)
			(layer "F.CrtYd")
		)
		(fp_rect
			(start -0.508 0.9398)
			(end 0.508 -0.9398)
			(stroke
				(width 0)
				(type default)
			)
			(fill no)
			(layer "F.Fab")
		)
		(pad "1" smd custom
			(at 0 -0.4445 270)
			(size 0.1397 0.1397)
			(layers "F.Cu" "F.Mask" "F.Paste")
			(net "SSD_PERST#12")
			(options
				(clearance outline)
				(anchor circle)
			)
			(primitives
				(gr_poly
					(pts
						(arc
							(start -0.1778 -0.2794)
							(mid -0.249642 -0.249642)
							(end -0.2794 -0.1778)
						)
						(arc
							(start -0.2794 0.1778)
							(mid -0.249642 0.249642)
							(end -0.1778 0.2794)
						)
						(arc
							(start 0.1778 0.2794)
							(mid 0.249642 0.249642)
							(end 0.2794 0.1778)
						)
						(arc
							(start 0.2794 -0.1778)
							(mid 0.249642 -0.249642)
							(end 0.1778 -0.2794)
						)
					)
					(width 0)
					(fill yes)
				)
			)
		)
		(pad "2" smd custom
			(at 0 0.4445 270)
			(size 0.1397 0.1397)
			(layers "F.Cu" "F.Mask" "F.Paste")
			(net "GND")
			(options
				(clearance outline)
				(anchor circle)
			)
			(primitives
				(gr_poly
					(pts
						(arc
							(start -0.1778 -0.2794)
							(mid -0.249642 -0.249642)
							(end -0.2794 -0.1778)
						)
						(arc
							(start -0.2794 0.1778)
							(mid -0.249642 0.249642)
							(end -0.1778 0.2794)
						)
						(arc
							(start 0.1778 0.2794)
							(mid 0.249642 0.249642)
							(end 0.2794 0.1778)
						)
						(arc
							(start 0.2794 -0.1778)
							(mid 0.249642 -0.249642)
							(end 0.1778 -0.2794)
						)
					)
					(width 0)
					(fill yes)
				)
			)
		)
	)
	(footprint ""
		(layer "F.Cu")
		(at 25.420066 -107.954318 180)
		(property "Reference" "R9045"
			(at 0 0 180)
			(layer "F.SilkS")
			(hide yes)
			(effects
				(font
					(size 1.27 1.27)
				)
			)
		)
		(property "Value" "470R2F-GP"
			(at 0.064008 -3.993896 180)
			(unlocked yes)
			(layer "F.Fab")
			(hide yes)
			(effects
				(font
					(size 1.016 1.016)
					(thickness 0.1524)
				)
			)
		)
		(property "Device Type" "R402H16"
			(at 0.064008 -5.517896 180)
			(unlocked yes)
			(layer "F.Fab")
			(hide yes)
			(effects
				(font
					(size 1.016 1.016)
					(thickness 0.1524)
				)
			)
		)
		(duplicate_pad_numbers_are_jumpers no)
		(fp_line
			(start 0.508 -0.9398)
			(end -0.508 -0.9398)
			(stroke
				(width 0.1524)
				(type default)
			)
			(layer "F.SilkS")
		)
		(fp_line
			(start -0.508 -0.9398)
			(end -0.508 0.9398)
			(stroke
				(width 0.1524)
				(type default)
			)
			(layer "F.SilkS")
		)
		(fp_rect
			(start -0.508 0.9398)
			(end 0.508 -0.9398)
			(stroke
				(width 0)
				(type default)
			)
			(fill no)
			(layer "F.CrtYd")
		)
		(fp_rect
			(start -0.508 0.9398)
			(end 0.508 -0.9398)
			(stroke
				(width 0)
				(type default)
			)
			(fill no)
			(layer "F.Fab")
		)
		(pad "1" smd custom
			(at 0 -0.4445 180)
			(size 0.1397 0.1397)
			(layers "F.Cu" "F.Mask" "F.Paste")
			(net "P3V3_STBY")
			(options
				(clearance outline)
				(anchor circle)
			)
			(primitives
				(gr_poly
					(pts
						(arc
							(start -0.1778 -0.2794)
							(mid -0.249642 -0.249642)
							(end -0.2794 -0.1778)
						)
						(arc
							(start -0.2794 0.1778)
							(mid -0.249642 0.249642)
							(end -0.1778 0.2794)
						)
						(arc
							(start 0.1778 0.2794)
							(mid 0.249642 0.249642)
							(end 0.2794 0.1778)
						)
						(arc
							(start 0.2794 -0.1778)
							(mid 0.249642 -0.249642)
							(end 0.1778 -0.2794)
						)
					)
					(width 0)
					(fill yes)
				)
			)
		)
		(pad "2" smd custom
			(at 0 0.4445 180)
			(size 0.1397 0.1397)
			(layers "F.Cu" "F.Mask" "F.Paste")
			(net "BMC_REFCLK_N")
			(options
				(clearance outline)
				(anchor circle)
			)
			(primitives
				(gr_poly
					(pts
						(arc
							(start -0.1778 -0.2794)
							(mid -0.249642 -0.249642)
							(end -0.2794 -0.1778)
						)
						(arc
							(start -0.2794 0.1778)
							(mid -0.249642 0.249642)
							(end -0.1778 0.2794)
						)
						(arc
							(start 0.1778 0.2794)
							(mid 0.249642 0.249642)
							(end 0.2794 0.1778)
						)
						(arc
							(start 0.2794 -0.1778)
							(mid 0.249642 -0.249642)
							(end 0.1778 -0.2794)
						)
					)
					(width 0)
					(fill yes)
				)
			)
		)
	)
	(footprint ""
		(layer "F.Cu")
		(at 115.7732 -26.5938 180)
		(property "Reference" "R644"
			(at 0 0 180)
			(layer "F.SilkS")
			(hide yes)
			(effects
				(font
					(size 1.27 1.27)
				)
			)
		)
		(property "Value" "4K7R2F-GP"
			(at 0.064008 -3.993896 180)
			(unlocked yes)
			(layer "F.Fab")
			(hide yes)
			(effects
				(font
					(size 1.016 1.016)
					(thickness 0.1524)
				)
			)
		)
		(property "Device Type" "R402H16"
			(at 0.064008 -5.517896 180)
			(unlocked yes)
			(layer "F.Fab")
			(hide yes)
			(effects
				(font
					(size 1.016 1.016)
					(thickness 0.1524)
				)
			)
		)
		(duplicate_pad_numbers_are_jumpers no)
		(fp_line
			(start 0.508 -0.9398)
			(end -0.508 -0.9398)
			(stroke
				(width 0.1524)
				(type default)
			)
			(layer "F.SilkS")
		)
		(fp_line
			(start -0.508 -0.9398)
			(end -0.508 0.9398)
			(stroke
				(width 0.1524)
				(type default)
			)
			(layer "F.SilkS")
		)
		(fp_rect
			(start -0.508 0.9398)
			(end 0.508 -0.9398)
			(stroke
				(width 0)
				(type default)
			)
			(fill no)
			(layer "F.CrtYd")
		)
		(fp_rect
			(start -0.508 0.9398)
			(end 0.508 -0.9398)
			(stroke
				(width 0)
				(type default)
			)
			(fill no)
			(layer "F.Fab")
		)
		(pad "1" smd custom
			(at 0 -0.4445 180)
			(size 0.1397 0.1397)
			(layers "F.Cu" "F.Mask" "F.Paste")
			(net "HOST_I2C_RESET_N")
			(options
				(clearance outline)
				(anchor circle)
			)
			(primitives
				(gr_poly
					(pts
						(arc
							(start -0.1778 -0.2794)
							(mid -0.249642 -0.249642)
							(end -0.2794 -0.1778)
						)
						(arc
							(start -0.2794 0.1778)
							(mid -0.249642 0.249642)
							(end -0.1778 0.2794)
						)
						(arc
							(start 0.1778 0.2794)
							(mid 0.249642 0.249642)
							(end 0.2794 0.1778)
						)
						(arc
							(start 0.2794 -0.1778)
							(mid 0.249642 -0.249642)
							(end 0.1778 -0.2794)
						)
					)
					(width 0)
					(fill yes)
				)
			)
		)
		(pad "2" smd custom
			(at 0 0.4445 180)
			(size 0.1397 0.1397)
			(layers "F.Cu" "F.Mask" "F.Paste")
			(net "P3V3_STBY")
			(options
				(clearance outline)
				(anchor circle)
			)
			(primitives
				(gr_poly
					(pts
						(arc
							(start -0.1778 -0.2794)
							(mid -0.249642 -0.249642)
							(end -0.2794 -0.1778)
						)
						(arc
							(start -0.2794 0.1778)
							(mid -0.249642 0.249642)
							(end -0.1778 0.2794)
						)
						(arc
							(start 0.1778 0.2794)
							(mid 0.249642 0.249642)
							(end 0.2794 0.1778)
						)
						(arc
							(start 0.2794 -0.1778)
							(mid 0.249642 -0.249642)
							(end 0.1778 -0.2794)
						)
					)
					(width 0)
					(fill yes)
				)
			)
		)
	)
	(footprint ""
		(layer "F.Cu")
		(at 9.906 -123.063 90)
		(property "Reference" "R293"
			(at 0 0 90)
			(layer "F.SilkS")
			(hide yes)
			(effects
				(font
					(size 1.27 1.27)
				)
			)
		)
		(property "Value" "4K7R2F-GP"
			(at 0.064008 -3.993896 90)
			(unlocked yes)
			(layer "F.Fab")
			(hide yes)
			(effects
				(font
					(size 1.016 1.016)
					(thickness 0.1524)
				)
			)
		)
		(property "Device Type" "R402H16"
			(at 0.064008 -5.517896 90)
			(unlocked yes)
			(layer "F.Fab")
			(hide yes)
			(effects
				(font
					(size 1.016 1.016)
					(thickness 0.1524)
				)
			)
		)
		(duplicate_pad_numbers_are_jumpers no)
		(fp_line
			(start 0.508 -0.9398)
			(end -0.508 -0.9398)
			(stroke
				(width 0.1524)
				(type default)
			)
			(layer "F.SilkS")
		)
		(fp_line
			(start -0.508 -0.9398)
			(end -0.508 0.9398)
			(stroke
				(width 0.1524)
				(type default)
			)
			(layer "F.SilkS")
		)
		(fp_rect
			(start -0.508 0.9398)
			(end 0.508 -0.9398)
			(stroke
				(width 0)
				(type default)
			)
			(fill no)
			(layer "F.CrtYd")
		)
		(fp_rect
			(start -0.508 0.9398)
			(end 0.508 -0.9398)
			(stroke
				(width 0)
				(type default)
			)
			(fill no)
			(layer "F.Fab")
		)
		(pad "1" smd custom
			(at 0 -0.4445 90)
			(size 0.1397 0.1397)
			(layers "F.Cu" "F.Mask" "F.Paste")
			(net "P3V3_STBY")
			(options
				(clearance outline)
				(anchor circle)
			)
			(primitives
				(gr_poly
					(pts
						(arc
							(start -0.1778 -0.2794)
							(mid -0.249642 -0.249642)
							(end -0.2794 -0.1778)
						)
						(arc
							(start -0.2794 0.1778)
							(mid -0.249642 0.249642)
							(end -0.1778 0.2794)
						)
						(arc
							(start 0.1778 0.2794)
							(mid 0.249642 0.249642)
							(end 0.2794 0.1778)
						)
						(arc
							(start 0.2794 -0.1778)
							(mid 0.249642 -0.249642)
							(end 0.1778 -0.2794)
						)
					)
					(width 0)
					(fill yes)
				)
			)
		)
		(pad "2" smd custom
			(at 0 0.4445 90)
			(size 0.1397 0.1397)
			(layers "F.Cu" "F.Mask" "F.Paste")
			(net "I2C1_LS_G2")
			(options
				(clearance outline)
				(anchor circle)
			)
			(primitives
				(gr_poly
					(pts
						(arc
							(start -0.1778 -0.2794)
							(mid -0.249642 -0.249642)
							(end -0.2794 -0.1778)
						)
						(arc
							(start -0.2794 0.1778)
							(mid -0.249642 0.249642)
							(end -0.1778 0.2794)
						)
						(arc
							(start 0.1778 0.2794)
							(mid 0.249642 0.249642)
							(end 0.2794 0.1778)
						)
						(arc
							(start 0.2794 -0.1778)
							(mid 0.249642 -0.249642)
							(end 0.1778 -0.2794)
						)
					)
					(width 0)
					(fill yes)
				)
			)
		)
	)
	(footprint ""
		(layer "F.Cu")
		(at 157.592268 -212.420454 180)
		(property "Reference" "C168"
			(at 0 0 180)
			(layer "F.SilkS")
			(hide yes)
			(effects
				(font
					(size 1.27 1.27)
				)
			)
		)
		(property "Value" "SCD22U10V2KX-1GP"
			(at 1.1811 -2.7051 180)
			(unlocked yes)
			(layer "F.Fab")
			(hide yes)
			(effects
				(font
					(size 1.016 1.016)
					(thickness 0.1524)
				)
			)
		)
		(property "Device Type" "C402H22"
			(at 1.1811 -4.2291 180)
			(unlocked yes)
			(layer "F.Fab")
			(hide yes)
			(effects
				(font
					(size 1.016 1.016)
					(thickness 0.1524)
				)
			)
		)
		(duplicate_pad_numbers_are_jumpers no)
		(fp_rect
			(start -0.4318 0.9525)
			(end 0.4318 -0.9525)
			(stroke
				(width 0)
				(type default)
			)
			(fill no)
			(layer "F.CrtYd")
		)
		(fp_rect
			(start -0.4318 0.9525)
			(end 0.4318 -0.9525)
			(stroke
				(width 0)
				(type default)
			)
			(fill no)
			(layer "F.Fab")
		)
		(pad "1" smd custom
			(at 0 -0.4445 180)
			(size 0.1524 0.1524)
			(layers "F.Cu" "F.Mask" "F.Paste")
			(net "PCIE_TX_CAP_P53")
			(options
				(clearance outline)
				(anchor circle)
			)
			(primitives
				(gr_poly
					(pts
						(arc
							(start 0.3048 -0.2032)
							(mid 0.275042 -0.275042)
							(end 0.2032 -0.3048)
						)
						(arc
							(start -0.2032 -0.3048)
							(mid -0.275042 -0.275042)
							(end -0.3048 -0.2032)
						)
						(arc
							(start -0.3048 0.2032)
							(mid -0.275042 0.275042)
							(end -0.2032 0.3048)
						)
						(arc
							(start 0.2032 0.3048)
							(mid 0.275042 0.275042)
							(end 0.3048 0.2032)
						)
					)
					(width 0)
					(fill yes)
				)
			)
		)
		(pad "2" smd custom
			(at 0 0.4445 180)
			(size 0.1524 0.1524)
			(layers "F.Cu" "F.Mask" "F.Paste")
			(net "PCIE_TX_P53")
			(options
				(clearance outline)
				(anchor circle)
			)
			(primitives
				(gr_poly
					(pts
						(arc
							(start 0.3048 -0.2032)
							(mid 0.275042 -0.275042)
							(end 0.2032 -0.3048)
						)
						(arc
							(start -0.2032 -0.3048)
							(mid -0.275042 -0.275042)
							(end -0.3048 -0.2032)
						)
						(arc
							(start -0.3048 0.2032)
							(mid -0.275042 0.275042)
							(end -0.2032 0.3048)
						)
						(arc
							(start 0.2032 0.3048)
							(mid 0.275042 0.275042)
							(end 0.3048 0.2032)
						)
					)
					(width 0)
					(fill yes)
				)
			)
		)
	)
	(footprint ""
		(layer "F.Cu")
		(at 37.94252 -44.661074 180)
		(property "Reference" "U22"
			(at 0 0 180)
			(layer "F.SilkS")
			(hide yes)
			(effects
				(font
					(size 1.27 1.27)
				)
			)
		)
		(property "Value" "AZC099-04S-1-GP"
			(at -0.0254 -11.9634 180)
			(unlocked yes)
			(layer "F.Fab")
			(hide yes)
			(effects
				(font
					(size 1.016 1.016)
					(thickness 0.1524)
				)
			)
		)
		(property "Device Type" "SOT-6H58"
			(at -0.0254 -13.5636 180)
			(unlocked yes)
			(layer "F.Fab")
			(hide yes)
			(effects
				(font
					(size 1.016 1.016)
					(thickness 0.1524)
				)
			)
		)
		(duplicate_pad_numbers_are_jumpers no)
		(fp_line
			(start 1.7145 0.5842)
			(end 1.7145 -0.5842)
			(stroke
				(width 0.1524)
				(type default)
			)
			(layer "F.SilkS")
		)
		(fp_line
			(start 1.7145 -0.5842)
			(end -1.9685 -0.5842)
			(stroke
				(width 0.1524)
				(type default)
			)
			(layer "F.SilkS")
		)
		(fp_line
			(start -1.5621 0)
			(end -1.9685 0.4064)
			(stroke
				(width 0.1524)
				(type default)
			)
			(layer "F.SilkS")
		)
		(fp_line
			(start -1.9685 0.5842)
			(end 1.7145 0.5842)
			(stroke
				(width 0.1524)
				(type default)
			)
			(layer "F.SilkS")
		)
		(fp_line
			(start -1.9685 0.5842)
			(end -1.9685 2.3622)
			(stroke
				(width 0.508)
				(type default)
			)
			(layer "F.SilkS")
		)
		(fp_line
			(start -1.9685 -0.4064)
			(end -1.5621 0)
			(stroke
				(width 0.1524)
				(type default)
			)
			(layer "F.SilkS")
		)
		(fp_line
			(start -1.9685 -0.5842)
			(end -1.9685 0.5842)
			(stroke
				(width 0.1524)
				(type default)
			)
			(layer "F.SilkS")
		)
		(fp_poly
			(pts
				(xy -1.27 -0.635) (xy 1.27 -0.635) (xy 1.27 0.635) (xy -1.27 0.635)
			)
			(stroke
				(width 0)
				(type default)
			)
			(fill yes)
			(layer "F.SilkS")
		)
		(fp_rect
			(start -1.9685 2.3622)
			(end 1.9685 -2.3622)
			(stroke
				(width 0)
				(type default)
			)
			(fill no)
			(layer "F.CrtYd")
		)
		(fp_poly
			(pts
				(xy -1.9685 -2.3622) (xy 1.9685 -2.3622) (xy 1.9685 2.3622) (xy -1.9685 2.3622)
			)
			(stroke
				(width 0)
				(type default)
			)
			(fill no)
			(layer "F.Fab")
		)
		(pad "1" smd rect
			(at -0.9525 1.3462 180)
			(size 0.5842 1.016)
			(layers "F.Cu" "F.Mask" "F.Paste")
			(net "USB_P1_F_DP1")
		)
		(pad "2" smd rect
			(at 0 1.3462 180)
			(size 0.5842 1.016)
			(layers "F.Cu" "F.Mask" "F.Paste")
			(net "GND")
		)
		(pad "3" smd rect
			(at 0.9525 1.3462 180)
			(size 0.5842 1.016)
			(layers "F.Cu" "F.Mask" "F.Paste")
			(net "Net_2090")
		)
		(pad "4" smd rect
			(at 0.9525 -1.3462 180)
			(size 0.5842 1.016)
			(layers "F.Cu" "F.Mask" "F.Paste")
			(net "Net_2091")
		)
		(pad "5" smd rect
			(at 0 -1.3462 180)
			(size 0.5842 1.016)
			(layers "F.Cu" "F.Mask" "F.Paste")
			(net "P5V_USB")
		)
		(pad "6" smd rect
			(at -0.9525 -1.3462 180)
			(size 0.5842 1.016)
			(layers "F.Cu" "F.Mask" "F.Paste")
			(net "USB_P1_F_DN1")
		)
	)
)
